(kicad_pcb
	(version 20260206)
	(generator "pcbnew")
	(generator_version "10.0")
	(general
		(thickness 0.77096)
		(legacy_teardrops no)
	)
	(paper "A4")
	(title_block
		(title "gnss-m2-neo-m9n — M2_NEO-M9N_MODULE.PcbDoc")
		(comment 1 "Time Appliance Project (Time Card) / footprints 23-26 of 40")
	)
	(layers
		(0 "F.Cu" signal "L01-Top Layer")
		(4 "In1.Cu" signal "L02-Inner Layer")
		(6 "In2.Cu" signal "L03-Inner Layer")
		(2 "B.Cu" signal "L04-Bottom Layer")
		(9 "F.Adhes" user "F.Adhesive")
		(11 "B.Adhes" user "B.Adhesive")
		(13 "F.Paste" user "Top Paste")
		(15 "B.Paste" user "Bottom Paste")
		(5 "F.SilkS" user "Top Overlay")
		(7 "B.SilkS" user "Bottom Overlay")
		(1 "F.Mask" user "Top Solder")
		(3 "B.Mask" user "Bottom Solder")
		(17 "Dwgs.User" user "User.Drawings")
		(19 "Cmts.User" user "User.Comments")
		(21 "Eco1.User" user "User.Eco1")
		(23 "Eco2.User" user "User.Eco2")
		(25 "Edge.Cuts" user)
		(27 "Margin" user)
		(31 "F.CrtYd" user "Top Courtyard")
		(29 "B.CrtYd" user "Bottom Courtyard")
		(35 "F.Fab" user "Top Component Outline")
		(33 "B.Fab" user "Bottom Component Outline 2")
	)
	(footprint "MyLibrary:IC_NEO-M9N"
		(layer "F.Cu")
		(at 148.401105 102.1036 90)
		(property "Reference" "U1"
			(at -6.722433 -8.722195 0)
			(unlocked yes)
			(layer "F.SilkS")
			(effects
				(font
					(size 0.635 0.635)
					(thickness 0.1778)
				)
			)
		)
		(property "Value" "NEO-M9N-00B"
			(at -1.74154 9.661983 90)
			(unlocked yes)
			(layer "F.SilkS")
			(hide yes)
			(effects
				(font
					(size 0.635 0.635)
					(thickness 0.1778)
				)
			)
		)
		(sheetname "01-M2_NEO-M9N_MODULE")
		(sheetfile "01-M2_NEO-M9N_MODULE.kicad_sch")
		(duplicate_pad_numbers_are_jumpers no)
		(fp_line
			(start 7.1755 -8.025)
			(end 7.1755 8.025)
			(stroke
				(width 0.1778)
				(type solid)
			)
			(layer "F.SilkS")
		)
		(fp_line
			(start -7.1755 -8.025)
			(end 7.1755 -8.025)
			(stroke
				(width 0.1778)
				(type solid)
			)
			(layer "F.SilkS")
		)
		(fp_line
			(start -7.1755 -8.025)
			(end -7.1755 8.025)
			(stroke
				(width 0.1778)
				(type solid)
			)
			(layer "F.SilkS")
		)
		(fp_line
			(start -7.1755 8.025)
			(end 7.1755 8.025)
			(stroke
				(width 0.1778)
				(type solid)
			)
			(layer "F.SilkS")
		)
		(fp_rect
			(start 3.69996 8.02496)
			(end 7.17546 7.57496)
			(stroke
				(width 0)
				(type default)
			)
			(fill yes)
			(layer "F.SilkS")
		)
		(fp_rect
			(start -5.80171 -7.40111)
			(end -7.00821 -6.60101)
			(stroke
				(width 0)
				(type default)
			)
			(fill yes)
			(layer "F.Paste")
		)
		(fp_rect
			(start -4.915885 -7.299505)
			(end -5.811235 -6.702605)
			(stroke
				(width 0)
				(type default)
			)
			(fill yes)
			(layer "F.Paste")
		)
		(fp_rect
			(start 4.915555 -6.702625)
			(end 5.810905 -7.299525)
			(stroke
				(width 0)
				(type default)
			)
			(fill yes)
			(layer "F.Paste")
		)
		(fp_rect
			(start 5.80138 -6.60103)
			(end 7.00788 -7.40113)
			(stroke
				(width 0)
				(type default)
			)
			(fill yes)
			(layer "F.Paste")
		)
		(fp_rect
			(start -5.8017 -6.30105)
			(end -7.0082 -5.50095)
			(stroke
				(width 0)
				(type default)
			)
			(fill yes)
			(layer "F.Paste")
		)
		(fp_rect
			(start -4.915875 -6.199455)
			(end -5.811225 -5.602555)
			(stroke
				(width 0)
				(type default)
			)
			(fill yes)
			(layer "F.Paste")
		)
		(fp_rect
			(start 4.915575 -5.602555)
			(end 5.810925 -6.199455)
			(stroke
				(width 0)
				(type default)
			)
			(fill yes)
			(layer "F.Paste")
		)
		(fp_rect
			(start 5.8014 -5.50095)
			(end 7.0079 -6.30105)
			(stroke
				(width 0)
				(type default)
			)
			(fill yes)
			(layer "F.Paste")
		)
		(fp_rect
			(start -5.80171 -5.20111)
			(end -7.00821 -4.40101)
			(stroke
				(width 0)
				(type default)
			)
			(fill yes)
			(layer "F.Paste")
		)
		(fp_rect
			(start -4.915885 -5.099505)
			(end -5.811235 -4.502605)
			(stroke
				(width 0)
				(type default)
			)
			(fill yes)
			(layer "F.Paste")
		)
		(fp_rect
			(start 4.915555 -4.502625)
			(end 5.810905 -5.099525)
			(stroke
				(width 0)
				(type default)
			)
			(fill yes)
			(layer "F.Paste")
		)
		(fp_rect
			(start 5.80138 -4.40102)
			(end 7.00788 -5.20112)
			(stroke
				(width 0)
				(type default)
			)
			(fill yes)
			(layer "F.Paste")
		)
		(fp_rect
			(start -5.8017 -4.10105)
			(end -7.0082 -3.30095)
			(stroke
				(width 0)
				(type default)
			)
			(fill yes)
			(layer "F.Paste")
		)
		(fp_rect
			(start -4.915875 -3.999455)
			(end -5.811225 -3.402555)
			(stroke
				(width 0)
				(type default)
			)
			(fill yes)
			(layer "F.Paste")
		)
		(fp_rect
			(start 4.915575 -3.402555)
			(end 5.810925 -3.999455)
			(stroke
				(width 0)
				(type default)
			)
			(fill yes)
			(layer "F.Paste")
		)
		(fp_rect
			(start 5.8014 -3.30095)
			(end 7.0079 -4.10105)
			(stroke
				(width 0)
				(type default)
			)
			(fill yes)
			(layer "F.Paste")
		)
		(fp_rect
			(start -5.8017 -3.00105)
			(end -7.0082 -2.20095)
			(stroke
				(width 0)
				(type default)
			)
			(fill yes)
			(layer "F.Paste")
		)
		(fp_rect
			(start -4.915875 -2.899455)
			(end -5.811225 -2.302555)
			(stroke
				(width 0)
				(type default)
			)
			(fill yes)
			(layer "F.Paste")
		)
		(fp_rect
			(start 4.915575 -2.302555)
			(end 5.810925 -2.899455)
			(stroke
				(width 0)
				(type default)
			)
			(fill yes)
			(layer "F.Paste")
		)
		(fp_rect
			(start 5.8014 -2.20095)
			(end 7.0079 -3.00105)
			(stroke
				(width 0)
				(type default)
			)
			(fill yes)
			(layer "F.Paste")
		)
		(fp_rect
			(start -5.80176 -0.00103)
			(end -7.00826 0.79907)
			(stroke
				(width 0)
				(type default)
			)
			(fill yes)
			(layer "F.Paste")
		)
		(fp_rect
			(start -4.915905 0.100475)
			(end -5.811255 0.697375)
			(stroke
				(width 0)
				(type default)
			)
			(fill yes)
			(layer "F.Paste")
		)
		(fp_rect
			(start 4.915535 0.697355)
			(end 5.810885 0.100455)
			(stroke
				(width 0)
				(type default)
			)
			(fill yes)
			(layer "F.Paste")
		)
		(fp_rect
			(start 5.80134 0.79907)
			(end 7.00784 -0.00103)
			(stroke
				(width 0)
				(type default)
			)
			(fill yes)
			(layer "F.Paste")
		)
		(fp_rect
			(start -5.8017 1.09895)
			(end -7.0082 1.89905)
			(stroke
				(width 0)
				(type default)
			)
			(fill yes)
			(layer "F.Paste")
		)
		(fp_rect
			(start -4.915875 1.200545)
			(end -5.811225 1.797445)
			(stroke
				(width 0)
				(type default)
			)
			(fill yes)
			(layer "F.Paste")
		)
		(fp_rect
			(start 4.915575 1.797445)
			(end 5.810925 1.200545)
			(stroke
				(width 0)
				(type default)
			)
			(fill yes)
			(layer "F.Paste")
		)
		(fp_rect
			(start 5.8014 1.89905)
			(end 7.0079 1.09895)
			(stroke
				(width 0)
				(type default)
			)
			(fill yes)
			(layer "F.Paste")
		)
		(fp_rect
			(start -5.80173 2.19887)
			(end -7.00823 2.99897)
			(stroke
				(width 0)
				(type default)
			)
			(fill yes)
			(layer "F.Paste")
		)
		(fp_rect
			(start -4.915905 2.300475)
			(end -5.811255 2.897375)
			(stroke
				(width 0)
				(type default)
			)
			(fill yes)
			(layer "F.Paste")
		)
		(fp_rect
			(start 4.915535 2.897355)
			(end 5.810885 2.300455)
			(stroke
				(width 0)
				(type default)
			)
			(fill yes)
			(layer "F.Paste")
		)
		(fp_rect
			(start 5.80136 2.99896)
			(end 7.00786 2.19886)
			(stroke
				(width 0)
				(type default)
			)
			(fill yes)
			(layer "F.Paste")
		)
		(fp_rect
			(start -5.80173 3.29887)
			(end -7.00823 4.09897)
			(stroke
				(width 0)
				(type default)
			)
			(fill yes)
			(layer "F.Paste")
		)
		(fp_rect
			(start -4.915905 3.400465)
			(end -5.811255 3.997365)
			(stroke
				(width 0)
				(type default)
			)
			(fill yes)
			(layer "F.Paste")
		)
		(fp_rect
			(start 4.915535 3.997355)
			(end 5.810885 3.400455)
			(stroke
				(width 0)
				(type default)
			)
			(fill yes)
			(layer "F.Paste")
		)
		(fp_rect
			(start 5.80136 4.09895)
			(end 7.00786 3.29885)
			(stroke
				(width 0)
				(type default)
			)
			(fill yes)
			(layer "F.Paste")
		)
		(fp_rect
			(start -5.8017 4.39895)
			(end -7.0082 5.19905)
			(stroke
				(width 0)
				(type default)
			)
			(fill yes)
			(layer "F.Paste")
		)
		(fp_rect
			(start -4.915875 4.500545)
			(end -5.811225 5.097445)
			(stroke
				(width 0)
				(type default)
			)
			(fill yes)
			(layer "F.Paste")
		)
		(fp_rect
			(start 4.915575 5.097445)
			(end 5.810925 4.500545)
			(stroke
				(width 0)
				(type default)
			)
			(fill yes)
			(layer "F.Paste")
		)
		(fp_rect
			(start 5.8014 5.19905)
			(end 7.0079 4.39895)
			(stroke
				(width 0)
				(type default)
			)
			(fill yes)
			(layer "F.Paste")
		)
		(fp_rect
			(start -5.80173 5.49887)
			(end -7.00823 6.29897)
			(stroke
				(width 0)
				(type default)
			)
			(fill yes)
			(layer "F.Paste")
		)
		(fp_rect
			(start -4.915905 5.600465)
			(end -5.811255 6.197365)
			(stroke
				(width 0)
				(type default)
			)
			(fill yes)
			(layer "F.Paste")
		)
		(fp_rect
			(start 4.915535 6.197355)
			(end 5.810885 5.600455)
			(stroke
				(width 0)
				(type default)
			)
			(fill yes)
			(layer "F.Paste")
		)
		(fp_rect
			(start 5.80136 6.29895)
			(end 7.00786 5.49885)
			(stroke
				(width 0)
				(type default)
			)
			(fill yes)
			(layer "F.Paste")
		)
		(fp_rect
			(start -5.8017 6.59895)
			(end -7.0082 7.39905)
			(stroke
				(width 0)
				(type default)
			)
			(fill yes)
			(layer "F.Paste")
		)
		(fp_rect
			(start -4.915875 6.700545)
			(end -5.811225 7.297445)
			(stroke
				(width 0)
				(type default)
			)
			(fill yes)
			(layer "F.Paste")
		)
		(fp_rect
			(start 4.915575 7.297445)
			(end 5.810925 6.700545)
			(stroke
				(width 0)
				(type default)
			)
			(fill yes)
			(layer "F.Paste")
		)
		(fp_rect
			(start 5.8014 7.39905)
			(end 7.0079 6.59895)
			(stroke
				(width 0)
				(type default)
			)
			(fill yes)
			(layer "F.Paste")
		)
		(pad "1" smd rect
			(at 6.09981 6.99897 90)
			(size 1.79832 0.8001)
			(layers "F.Cu" "F.Mask" "F.Paste")
			(net "SAFEBOOT_N")
			(solder_paste_margin -2147.48364)
		)
		(pad "2" smd rect
			(at 6.09981 5.89915 90)
			(size 1.79832 0.8001)
			(layers "F.Cu" "F.Mask" "F.Paste")
			(net "D_SEL")
			(solder_paste_margin -2147.48364)
		)
		(pad "3" smd rect
			(at 6.09981 4.79933 90)
			(size 1.79832 0.8001)
			(layers "F.Cu" "F.Mask" "F.Paste")
			(net "TP1")
			(solder_paste_margin -2147.48364)
		)
		(pad "4" smd rect
			(at 6.09981 3.69951 90)
			(size 1.79832 0.8001)
			(layers "F.Cu" "F.Mask" "F.Paste")
			(net "EXTIN")
			(solder_paste_margin -2147.48364)
		)
		(pad "5" smd rect
			(at 6.09981 2.59969 90)
			(size 1.79832 0.8001)
			(layers "F.Cu" "F.Mask" "F.Paste")
			(net "USB_DM")
			(solder_paste_margin -2147.48364)
		)
		(pad "6" smd rect
			(at 6.09981 1.49987 90)
			(size 1.79832 0.8001)
			(layers "F.Cu" "F.Mask" "F.Paste")
			(net "USB_DP")
			(solder_paste_margin -2147.48364)
		)
		(pad "7" smd rect
			(at 6.09981 0.40005 90)
			(size 1.79832 0.8001)
			(layers "F.Cu" "F.Mask" "F.Paste")
			(net "VDD_USB")
			(solder_paste_margin -2147.48364)
		)
		(pad "8" smd rect
			(at 6.09981 -2.59969 90)
			(size 1.79832 0.8001)
			(layers "F.Cu" "F.Mask" "F.Paste")
			(net "RST_GPS")
			(solder_paste_margin -2147.48364)
		)
		(pad "9" smd rect
			(at 6.09981 -3.69951 90)
			(size 1.79832 0.8001)
			(layers "F.Cu" "F.Mask" "F.Paste")
			(solder_paste_margin -2147.48364)
		)
		(pad "10" smd rect
			(at 6.09981 -4.79933 90)
			(size 1.79832 0.8001)
			(layers "F.Cu" "F.Mask" "F.Paste")
			(net "GND")
			(solder_paste_margin -2147.48364)
		)
		(pad "11" smd rect
			(at 6.09981 -5.89915 90)
			(size 1.79832 0.8001)
			(layers "F.Cu" "F.Mask" "F.Paste")
			(net "RF_MODULE")
			(solder_paste_margin -2147.48364)
		)
		(pad "12" smd rect
			(at 6.09981 -6.99897 90)
			(size 1.79832 0.8001)
			(layers "F.Cu" "F.Mask" "F.Paste")
			(net "GND")
			(solder_paste_margin -2147.48364)
		)
		(pad "13" smd rect
			(at -6.09981 -6.99897 90)
			(size 1.79832 0.8001)
			(layers "F.Cu" "F.Mask" "F.Paste")
			(net "GND")
			(solder_paste_margin -2147.48364)
		)
		(pad "14" smd rect
			(at -6.09981 -5.89915 90)
			(size 1.79832 0.8001)
			(layers "F.Cu" "F.Mask" "F.Paste")
			(net "LNA_EN")
			(solder_paste_margin -2147.48364)
		)
		(pad "15" smd rect
			(at -6.09981 -4.79933 90)
			(size 1.79832 0.8001)
			(layers "F.Cu" "F.Mask" "F.Paste")
			(solder_paste_margin -2147.48364)
		)
		(pad "16" smd rect
			(at -6.09981 -3.69951 90)
			(size 1.79832 0.8001)
			(layers "F.Cu" "F.Mask" "F.Paste")
			(solder_paste_margin -2147.48364)
		)
		(pad "17" smd rect
			(at -6.09981 -2.59969 90)
			(size 1.79832 0.8001)
			(layers "F.Cu" "F.Mask" "F.Paste")
			(solder_paste_margin -2147.48364)
		)
		(pad "18" smd rect
			(at -6.09981 0.40005 90)
			(size 1.79832 0.8001)
			(layers "F.Cu" "F.Mask" "F.Paste")
			(net "SDA")
			(solder_paste_margin -2147.48364)
		)
		(pad "19" smd rect
			(at -6.09981 1.49987 90)
			(size 1.79832 0.8001)
			(layers "F.Cu" "F.Mask" "F.Paste")
			(net "SCL")
			(solder_paste_margin -2147.48364)
		)
		(pad "20" smd rect
			(at -6.09981 2.59969 90)
			(size 1.79832 0.8001)
			(layers "F.Cu" "F.Mask" "F.Paste")
			(net "TX_GPS")
			(solder_paste_margin -2147.48364)
		)
		(pad "21" smd rect
			(at -6.09981 3.69951 90)
			(size 1.79832 0.8001)
			(layers "F.Cu" "F.Mask" "F.Paste")
			(net "RX_GPS")
			(solder_paste_margin -2147.48364)
		)
		(pad "22" smd rect
			(at -6.09981 4.79933 90)
			(size 1.79832 0.8001)
			(layers "F.Cu" "F.Mask" "F.Paste")
			(net "+3V3")
			(solder_paste_margin -2147.48364)
		)
		(pad "23" smd rect
			(at -6.09981 5.89915 90)
			(size 1.79832 0.8001)
			(layers "F.Cu" "F.Mask" "F.Paste")
			(net "+3V3")
			(solder_paste_margin -2147.48364)
		)
		(pad "24" smd rect
			(at -6.09981 6.99897 90)
			(size 1.79832 0.8001)
			(layers "F.Cu" "F.Mask" "F.Paste")
			(net "GND")
			(solder_paste_margin -2147.48364)
		)
	)
	(footprint "Vault:RESC1005X40X25NL05T05"
		(layer "F.Cu")
		(at 146.053395 113.66797 -90)
		(property "Reference" "R16"
			(at 1.73563 0.152214 90)
			(unlocked yes)
			(layer "F.SilkS")
			(effects
				(font
					(face "Arial")
					(size 0.48006 0.48006)
					(thickness 0.254)
				)
			)
		)
		(property "Value" "1K_1%_0402"
			(at -2.759202 7.27476 180)
			(unlocked yes)
			(layer "F.SilkS")
			(hide yes)
			(effects
				(font
					(size 1.524 1.524)
					(thickness 0.254)
				)
			)
		)
		(sheetname "01-M2_NEO-M9N_MODULE")
		(sheetfile "01-M2_NEO-M9N_MODULE.kicad_sch")
		(duplicate_pad_numbers_are_jumpers no)
		(fp_line
			(start -0.89999 0.45)
			(end -0.89999 -0.45)
			(stroke
				(width 0.05)
				(type solid)
			)
			(layer "F.CrtYd")
		)
		(fp_line
			(start 0.9 0.45)
			(end -0.89999 0.45)
			(stroke
				(width 0.05)
				(type solid)
			)
			(layer "F.CrtYd")
		)
		(fp_line
			(start 0.9 0.45)
			(end 0.9 -0.45)
			(stroke
				(width 0.05)
				(type solid)
			)
			(layer "F.CrtYd")
		)
		(fp_line
			(start 0 0.275)
			(end 0 -0.275)
			(stroke
				(width 0.1)
				(type solid)
			)
			(layer "F.CrtYd")
		)
		(fp_line
			(start 0.275 0)
			(end -0.27499 0)
			(stroke
				(width 0.1)
				(type solid)
			)
			(layer "F.CrtYd")
		)
		(fp_line
			(start 0.9 -0.45)
			(end -0.89999 -0.45)
			(stroke
				(width 0.05)
				(type solid)
			)
			(layer "F.CrtYd")
		)
		(pad "1" smd rect
			(at -0.45 0)
			(size 0.55 0.55)
			(layers "F.Cu" "F.Mask" "F.Paste")
			(net "NetLED1_1")
		)
		(pad "2" smd rect
			(at 0.45001 0)
			(size 0.55 0.55)
			(layers "F.Cu" "F.Mask" "F.Paste")
			(net "+3V3")
		)
	)
	(footprint "MyLibrary:r0603"
		(layer "F.Cu")
		(at 144.201105 91.6036 180)
		(property "Reference" "R4"
			(at 0.177805 -1.377557 180)
			(unlocked yes)
			(layer "F.SilkS")
			(effects
				(font
					(size 0.635 0.635)
					(thickness 0.1778)
				)
			)
		)
		(property "Value" "10 OHM 1/4W 0603"
			(at -5.216983 5.192245 90)
			(unlocked yes)
			(layer "F.SilkS")
			(hide yes)
			(effects
				(font
					(size 0.635 0.635)
					(thickness 0.1778)
				)
			)
		)
		(sheetname "01-M2_NEO-M9N_MODULE")
		(sheetfile "01-M2_NEO-M9N_MODULE.kicad_sch")
		(duplicate_pad_numbers_are_jumpers no)
		(fp_line
			(start 1.2954 0.6858)
			(end -1.2954 0.6858)
			(stroke
				(width 0.1778)
				(type solid)
			)
			(layer "F.SilkS")
		)
		(fp_line
			(start 1.2954 -0.6858)
			(end 1.2954 0.6858)
			(stroke
				(width 0.1778)
				(type solid)
			)
			(layer "F.SilkS")
		)
		(fp_line
			(start 1.2954 -0.6858)
			(end -1.2954 -0.6858)
			(stroke
				(width 0.1778)
				(type solid)
			)
			(layer "F.SilkS")
		)
		(fp_line
			(start -1.2954 -0.6858)
			(end -1.2954 0.6858)
			(stroke
				(width 0.1778)
				(type solid)
			)
			(layer "F.SilkS")
		)
		(pad "1" smd rect
			(at -0.75 0 180)
			(size 0.6 0.9)
			(layers "F.Cu" "F.Mask" "F.Paste")
			(net "NetQ1_3")
		)
		(pad "2" smd rect
			(at 0.75 0 180)
			(size 0.6 0.9)
			(layers "F.Cu" "F.Mask" "F.Paste")
			(net "NetC5_2")
		)
	)
	(footprint "Vault:RESC1005X40X25NL05T10"
		(layer "F.Cu")
		(at 145.501105 119.1036 -90)
		(property "Reference" "R13"
			(at 0.256 -1.273069 270)
			(unlocked yes)
			(layer "F.SilkS")
			(effects
				(font
					(size 0.762 0.762)
					(thickness 0.254)
				)
			)
		)
		(property "Value" "0_5%_0402"
			(at -2.759192 6.766925 180)
			(unlocked yes)
			(layer "F.SilkS")
			(hide yes)
			(effects
				(font
					(size 1.524 1.524)
					(thickness 0.254)
				)
			)
		)
		(sheetname "02-M2_GoldFingers")
		(sheetfile "02-M2_GoldFingers.kicad_sch")
		(duplicate_pad_numbers_are_jumpers no)
		(fp_line
			(start -0.9 0.45)
			(end -0.9 -0.45)
			(stroke
				(width 0.05)
				(type solid)
			)
			(layer "F.CrtYd")
		)
		(fp_line
			(start 0.9 0.45)
			(end -0.9 0.45)
			(stroke
				(width 0.05)
				(type solid)
			)
			(layer "F.CrtYd")
		)
		(fp_line
			(start 0.9 0.45)
			(end 0.9 -0.45)
			(stroke
				(width 0.05)
				(type solid)
			)
			(layer "F.CrtYd")
		)
		(fp_line
			(start 0 0.275)
			(end 0 -0.275)
			(stroke
				(width 0.1)
				(type solid)
			)
			(layer "F.CrtYd")
		)
		(fp_line
			(start 0.275 0)
			(end -0.275 0)
			(stroke
				(width 0.1)
				(type solid)
			)
			(layer "F.CrtYd")
		)
		(fp_line
			(start 0.9 -0.45)
			(end -0.9 -0.45)
			(stroke
				(width 0.05)
				(type solid)
			)
			(layer "F.CrtYd")
		)
		(pad "1" smd rect
			(at -0.425 0)
			(size 0.55 0.6)
			(layers "F.Cu" "F.Mask" "F.Paste")
			(net "RST_GPS")
		)
		(pad "2" smd rect
			(at 0.425 0)
			(size 0.55 0.6)
			(layers "F.Cu" "F.Mask" "F.Paste")
			(net "NetJ1_50")
		)
	)
)
